(kicad_pcb
	(version 20260206)
	(generator "pcbnew")
	(generator_version "10.0")
	(general
		(thickness 1.6)
		(legacy_teardrops no)
	)
	(paper "A4")
	(title_block
		(title "timecard-production-celestica-r4006 — R4006-B0001-02_R01.brd")
		(comment 1 "Time Appliance Project (Time Card) / footprints 1000-1005 of 1113")
	)
	(layers
		(0 "F.Cu" signal "TOP")
		(4 "In1.Cu" signal "L02_GND1")
		(6 "In2.Cu" signal "L03_SIG1")
		(8 "In3.Cu" signal "L04_GND2")
		(10 "In4.Cu" signal "L05_VCC1")
		(12 "In5.Cu" signal "L06_VCC2")
		(14 "In6.Cu" signal "L07_GND3")
		(16 "In7.Cu" signal "L08_SIG2")
		(18 "In8.Cu" signal "L09_GND4")
		(2 "B.Cu" signal "BOTTOM")
		(9 "F.Adhes" user "F.Adhesive")
		(11 "B.Adhes" user "B.Adhesive")
		(13 "F.Paste" user "Package Geometry/Pastemask Top")
		(15 "B.Paste" user "Package Geometry/Pastemask Bottom")
		(5 "F.SilkS" user "Ref Des/Silkscreen Top")
		(7 "B.SilkS" user "Ref Des/Silkscreen Bottom")
		(1 "F.Mask" user "Board Geometry/Soldermask Top")
		(3 "B.Mask" user "Board Geometry/Soldermask Bottom")
		(17 "Dwgs.User" user "User.Drawings")
		(19 "Cmts.User" user "User.Comments")
		(21 "Eco1.User" user "User.Eco1")
		(23 "Eco2.User" user "User.Eco2")
		(25 "Edge.Cuts" user "Board Geometry/Outline")
		(27 "Margin" user)
		(31 "F.CrtYd" user "Package Geometry/Place Bound Top")
		(29 "B.CrtYd" user "Package Geometry/Place Bound Bottom")
		(35 "F.Fab" user "Ref Des/Assembly Top")
		(33 "B.Fab" user "Ref Des/Assembly Bottom")
	)
	(footprint ""
		(layer "B.Cu")
		(at 111.34725 -45.823124 180)
		(property "Reference" "C206"
			(at 43.14825 -1.023874 0)
			(unlocked yes)
			(layer "B.SilkS")
			(effects
				(font
					(size 0.635 0.4064)
					(thickness 0.1524)
				)
				(justify mirror)
			)
		)
		(property "Value" "VAL*"
			(at 0 3.718306 180)
			(unlocked yes)
			(layer "B.Fab")
			(hide yes)
			(effects
				(font
					(size 0.7874 0.5842)
					(thickness 0.127)
				)
				(justify mirror)
			)
		)
		(property "Device Type" "CAPACITOR-G105-0B104-CK,0.1UF,A"
			(at 0 1.432306 180)
			(unlocked yes)
			(layer "B.Fab")
			(hide yes)
			(effects
				(font
					(size 0.7874 0.5842)
					(thickness 0.127)
				)
				(justify mirror)
			)
		)
		(property "User Part Number" "PARTNUM*"
			(at 0 2.575306 180)
			(unlocked yes)
			(layer "Cmts.User")
			(hide yes)
			(effects
				(font
					(size 0.7874 0.5842)
					(thickness 0.127)
				)
				(justify mirror)
			)
		)
		(property "Tolerance" "TOL*"
			(at 0 4.861306 180)
			(unlocked yes)
			(layer "Cmts.User")
			(hide yes)
			(effects
				(font
					(size 0.7874 0.5842)
					(thickness 0.127)
				)
				(justify mirror)
			)
		)
		(duplicate_pad_numbers_are_jumpers no)
		(fp_line
			(start 0.970026 0.4699)
			(end 0.970026 -0.4699)
			(stroke
				(width 0.1)
				(type default)
			)
			(layer "B.SilkS")
		)
		(fp_line
			(start 0.970026 -0.4699)
			(end -0.970026 -0.4699)
			(stroke
				(width 0.1)
				(type default)
			)
			(layer "B.SilkS")
		)
		(fp_line
			(start -0.970026 0.4699)
			(end 0.970026 0.4699)
			(stroke
				(width 0.1)
				(type default)
			)
			(layer "B.SilkS")
		)
		(fp_line
			(start -0.970026 -0.4699)
			(end -0.970026 0.4699)
			(stroke
				(width 0.1)
				(type default)
			)
			(layer "B.SilkS")
		)
		(fp_poly
			(pts
				(xy 0.970026 0.4699) (xy -0.970026 0.4699) (xy -0.970026 -0.4699) (xy 0.970026 -0.4699)
			)
			(stroke
				(width 0)
				(type default)
			)
			(fill no)
			(layer "B.CrtYd")
		)
		(fp_line
			(start 0.508 0.3048)
			(end 0.508 -0.3048)
			(stroke
				(width 0.1)
				(type default)
			)
			(layer "B.Fab")
		)
		(fp_line
			(start 0.508 -0.3048)
			(end -0.508 -0.3048)
			(stroke
				(width 0.1)
				(type default)
			)
			(layer "B.Fab")
		)
		(fp_line
			(start -0.508 0.3048)
			(end 0.508 0.3048)
			(stroke
				(width 0.1)
				(type default)
			)
			(layer "B.Fab")
		)
		(fp_line
			(start -0.508 -0.3048)
			(end -0.508 0.3048)
			(stroke
				(width 0.1)
				(type default)
			)
			(layer "B.Fab")
		)
		(pad "1" smd circle
			(at 0.500126 0)
			(size 0.635 0.635)
			(layers "B.Cu" "B.Mask" "B.Paste")
			(net "XP1R8V_FPGA_VCCAUX")
		)
		(pad "2" smd circle
			(at -0.500126 0)
			(size 0.635 0.635)
			(layers "B.Cu" "B.Mask" "B.Paste")
			(net "SG")
		)
	)
	(footprint ""
		(layer "B.Cu")
		(at 136.906 -41.275 90)
		(property "Reference" "C178"
			(at 0.762 1.73863 270)
			(unlocked yes)
			(layer "B.SilkS")
			(effects
				(font
					(size 0.7874 0.5842)
					(thickness 0.1524)
				)
				(justify mirror)
			)
		)
		(property "Value" "VAL*"
			(at -0.0762 2.067306 90)
			(unlocked yes)
			(layer "B.Fab")
			(hide yes)
			(effects
				(font
					(size 0.7874 0.5842)
					(thickness 0.1524)
				)
				(justify mirror)
			)
		)
		(property "Tolerance" "TOL*"
			(at -0.0762 3.032506 90)
			(unlocked yes)
			(layer "Cmts.User")
			(hide yes)
			(effects
				(font
					(size 0.7874 0.5842)
					(thickness 0.1524)
				)
				(justify mirror)
			)
		)
		(property "User Part Number" "PARTNUM*"
			(at -0.1016 4.023106 90)
			(unlocked yes)
			(layer "Cmts.User")
			(hide yes)
			(effects
				(font
					(size 0.7874 0.5842)
					(thickness 0.1524)
				)
				(justify mirror)
			)
		)
		(property "Device Type" "CAPACITOR-G105-0B104-CK,0.1UF,A"
			(at -0.0508 1.127506 90)
			(unlocked yes)
			(layer "B.Fab")
			(hide yes)
			(effects
				(font
					(size 0.7874 0.5842)
					(thickness 0.1524)
				)
				(justify mirror)
			)
		)
		(duplicate_pad_numbers_are_jumpers no)
		(fp_line
			(start 1.143 -0.5588)
			(end 1.143 0.5588)
			(stroke
				(width 0.1)
				(type default)
			)
			(layer "B.SilkS")
		)
		(fp_line
			(start -1.143 -0.5588)
			(end 1.143 -0.5588)
			(stroke
				(width 0.1)
				(type default)
			)
			(layer "B.SilkS")
		)
		(fp_line
			(start 1.143 0.5588)
			(end -1.143 0.5588)
			(stroke
				(width 0.1)
				(type default)
			)
			(layer "B.SilkS")
		)
		(fp_line
			(start -1.143 0.5588)
			(end -1.143 -0.5588)
			(stroke
				(width 0.1)
				(type default)
			)
			(layer "B.SilkS")
		)
		(fp_rect
			(start 1.143 -0.5588)
			(end -1.143 0.5588)
			(stroke
				(width 0)
				(type default)
			)
			(fill no)
			(layer "B.CrtYd")
		)
		(fp_line
			(start 0.508 -0.3048)
			(end 0.508 0.3048)
			(stroke
				(width 0.1)
				(type default)
			)
			(layer "B.Fab")
		)
		(fp_line
			(start -0.508 -0.3048)
			(end 0.508 -0.3048)
			(stroke
				(width 0.1)
				(type default)
			)
			(layer "B.Fab")
		)
		(fp_line
			(start 0.508 0.3048)
			(end -0.508 0.3048)
			(stroke
				(width 0.1)
				(type default)
			)
			(layer "B.Fab")
		)
		(fp_line
			(start -0.508 0.3048)
			(end -0.508 -0.3048)
			(stroke
				(width 0.1)
				(type default)
			)
			(layer "B.Fab")
		)
		(pad "1" smd rect
			(at 0.5334 0 270)
			(size 0.7112 0.6096)
			(layers "B.Cu" "B.Mask" "B.Paste")
			(net "XP1R0V_FPGA")
		)
		(pad "2" smd rect
			(at -0.5334 0 270)
			(size 0.7112 0.6096)
			(layers "B.Cu" "B.Mask" "B.Paste")
			(net "SG")
		)
		(zone
			(layer "B.Cu")
			(hatch none 0.5)
			(connect_pads
				(clearance 0)
			)
			(min_thickness 0.25)
			(keepout
				(tracks allowed)
				(vias not_allowed)
				(pads allowed)
				(copperpour not_allowed)
				(footprints allowed)
			)
			(placement
				(enabled no)
				(sheetname "")
			)
			(fill
				(thermal_gap 0.5)
				(thermal_bridge_width 0.5)
				(island_removal_mode 0)
			)
			(polygon
				(pts
					(xy 136.6012 -41.3512) (xy 136.6012 -41.1988) (xy 137.2108 -41.1988) (xy 137.2108 -41.3512)
				)
			)
		)
	)
	(footprint ""
		(layer "B.Cu")
		(at 100.347018 -38.823138 180)
		(property "Reference" "C117"
			(at 42.562018 -1.008888 0)
			(unlocked yes)
			(layer "B.SilkS")
			(effects
				(font
					(size 0.635 0.4064)
					(thickness 0.1524)
				)
				(justify mirror)
			)
		)
		(property "Value" "VAL*"
			(at 0 3.718306 180)
			(unlocked yes)
			(layer "B.Fab")
			(hide yes)
			(effects
				(font
					(size 0.7874 0.5842)
					(thickness 0.127)
				)
				(justify mirror)
			)
		)
		(property "Tolerance" "TOL*"
			(at 0 4.861306 180)
			(unlocked yes)
			(layer "Cmts.User")
			(hide yes)
			(effects
				(font
					(size 0.7874 0.5842)
					(thickness 0.127)
				)
				(justify mirror)
			)
		)
		(property "User Part Number" "PARTNUM*"
			(at 0 2.575306 180)
			(unlocked yes)
			(layer "Cmts.User")
			(hide yes)
			(effects
				(font
					(size 0.7874 0.5842)
					(thickness 0.127)
				)
				(justify mirror)
			)
		)
		(property "Device Type" "CAPACITOR-G105-0F475-BM,4.7UF,A"
			(at 0 1.432306 180)
			(unlocked yes)
			(layer "B.Fab")
			(hide yes)
			(effects
				(font
					(size 0.7874 0.5842)
					(thickness 0.127)
				)
				(justify mirror)
			)
		)
		(duplicate_pad_numbers_are_jumpers no)
		(fp_line
			(start 0.970026 0.4699)
			(end 0.970026 -0.4699)
			(stroke
				(width 0.1)
				(type default)
			)
			(layer "B.SilkS")
		)
		(fp_line
			(start 0.970026 -0.4699)
			(end -0.970026 -0.4699)
			(stroke
				(width 0.1)
				(type default)
			)
			(layer "B.SilkS")
		)
		(fp_line
			(start -0.970026 0.4699)
			(end 0.970026 0.4699)
			(stroke
				(width 0.1)
				(type default)
			)
			(layer "B.SilkS")
		)
		(fp_line
			(start -0.970026 -0.4699)
			(end -0.970026 0.4699)
			(stroke
				(width 0.1)
				(type default)
			)
			(layer "B.SilkS")
		)
		(fp_poly
			(pts
				(xy 0.970026 0.4699) (xy -0.970026 0.4699) (xy -0.970026 -0.4699) (xy 0.970026 -0.4699)
			)
			(stroke
				(width 0)
				(type default)
			)
			(fill no)
			(layer "B.CrtYd")
		)
		(fp_line
			(start 0.508 0.3048)
			(end 0.508 -0.3048)
			(stroke
				(width 0.1)
				(type default)
			)
			(layer "B.Fab")
		)
		(fp_line
			(start 0.508 -0.3048)
			(end -0.508 -0.3048)
			(stroke
				(width 0.1)
				(type default)
			)
			(layer "B.Fab")
		)
		(fp_line
			(start -0.508 0.3048)
			(end 0.508 0.3048)
			(stroke
				(width 0.1)
				(type default)
			)
			(layer "B.Fab")
		)
		(fp_line
			(start -0.508 -0.3048)
			(end -0.508 0.3048)
			(stroke
				(width 0.1)
				(type default)
			)
			(layer "B.Fab")
		)
		(pad "1" smd circle
			(at 0.500126 0)
			(size 0.635 0.635)
			(layers "B.Cu" "B.Mask" "B.Paste")
			(net "FPGA_MGTAVTT")
		)
		(pad "2" smd circle
			(at -0.500126 0)
			(size 0.635 0.635)
			(layers "B.Cu" "B.Mask" "B.Paste")
			(net "SG")
		)
	)
	(footprint ""
		(layer "B.Cu")
		(at 99.3648 -78.5368 180)
		(property "Reference" "R165"
			(at -0.5842 -2.37617 0)
			(unlocked yes)
			(layer "B.SilkS")
			(effects
				(font
					(size 0.7874 0.5842)
					(thickness 0.1524)
				)
				(justify mirror)
			)
		)
		(property "Value" "VAL*"
			(at -0.02032 2.13233 180)
			(unlocked yes)
			(layer "B.Fab")
			(hide yes)
			(effects
				(font
					(size 0.7874 0.5842)
					(thickness 0.1524)
				)
				(justify mirror)
			)
		)
		(property "Tolerance" "TOL*"
			(at -0.044704 3.05435 180)
			(unlocked yes)
			(layer "Cmts.User")
			(hide yes)
			(effects
				(font
					(size 0.7874 0.5842)
					(thickness 0.1524)
				)
				(justify mirror)
			)
		)
		(property "User Part Number" "PARTNUM*"
			(at -0.02032 4.024884 180)
			(unlocked yes)
			(layer "Cmts.User")
			(hide yes)
			(effects
				(font
					(size 0.7874 0.5842)
					(thickness 0.1524)
				)
				(justify mirror)
			)
		)
		(property "Device Type" "RESISTOR-G155-11002-01,10KOHM,A"
			(at -0.008382 1.210564 180)
			(unlocked yes)
			(layer "B.Fab")
			(hide yes)
			(effects
				(font
					(size 0.7874 0.5842)
					(thickness 0.1524)
				)
				(justify mirror)
			)
		)
		(duplicate_pad_numbers_are_jumpers no)
		(fp_line
			(start 1.143 0.5588)
			(end -1.143 0.5588)
			(stroke
				(width 0.1)
				(type default)
			)
			(layer "B.SilkS")
		)
		(fp_line
			(start 1.143 -0.5588)
			(end 1.143 0.5588)
			(stroke
				(width 0.1)
				(type default)
			)
			(layer "B.SilkS")
		)
		(fp_line
			(start -1.143 0.5588)
			(end -1.143 -0.5588)
			(stroke
				(width 0.1)
				(type default)
			)
			(layer "B.SilkS")
		)
		(fp_line
			(start -1.143 -0.5588)
			(end 1.143 -0.5588)
			(stroke
				(width 0.1)
				(type default)
			)
			(layer "B.SilkS")
		)
		(fp_rect
			(start 1.143 0.5588)
			(end -1.143 -0.5588)
			(stroke
				(width 0)
				(type default)
			)
			(fill no)
			(layer "B.CrtYd")
		)
		(fp_line
			(start 0.508 0.3048)
			(end -0.508 0.3048)
			(stroke
				(width 0.1)
				(type default)
			)
			(layer "B.Fab")
		)
		(fp_line
			(start 0.508 -0.3048)
			(end 0.508 0.3048)
			(stroke
				(width 0.1)
				(type default)
			)
			(layer "B.Fab")
		)
		(fp_line
			(start -0.508 0.3048)
			(end -0.508 -0.3048)
			(stroke
				(width 0.1)
				(type default)
			)
			(layer "B.Fab")
		)
		(fp_line
			(start -0.508 -0.3048)
			(end 0.508 -0.3048)
			(stroke
				(width 0.1)
				(type default)
			)
			(layer "B.Fab")
		)
		(pad "1" smd rect
			(at 0.5334 0)
			(size 0.7112 0.6096)
			(layers "B.Cu" "B.Mask" "B.Paste")
			(net "XP1R2V_EN_R")
		)
		(pad "2" smd rect
			(at -0.5334 0)
			(size 0.7112 0.6096)
			(layers "B.Cu" "B.Mask" "B.Paste")
			(net "SG")
		)
		(zone
			(layer "B.Cu")
			(hatch none 0.5)
			(connect_pads
				(clearance 0)
			)
			(min_thickness 0.25)
			(keepout
				(tracks allowed)
				(vias not_allowed)
				(pads allowed)
				(copperpour not_allowed)
				(footprints allowed)
			)
			(placement
				(enabled no)
				(sheetname "")
			)
			(fill
				(thermal_gap 0.5)
				(thermal_bridge_width 0.5)
				(island_removal_mode 0)
			)
			(polygon
				(pts
					(xy 99.2886 -78.8416) (xy 99.2886 -78.232) (xy 99.441 -78.232) (xy 99.441 -78.8416)
				)
			)
		)
	)
	(footprint ""
		(layer "B.Cu")
		(at 95.758 -20.066 90)
		(property "Reference" "C245"
			(at -0.381 2.11963 270)
			(unlocked yes)
			(layer "B.SilkS")
			(effects
				(font
					(size 0.7874 0.5842)
					(thickness 0.1524)
				)
				(justify mirror)
			)
		)
		(property "Value" "VAL*"
			(at -0.0762 2.067306 90)
			(unlocked yes)
			(layer "B.Fab")
			(hide yes)
			(effects
				(font
					(size 0.7874 0.5842)
					(thickness 0.1524)
				)
				(justify mirror)
			)
		)
		(property "Device Type" "CAPACITOR-G105-0B104-EK,0.1UF,A"
			(at -0.0508 1.127506 90)
			(unlocked yes)
			(layer "B.Fab")
			(hide yes)
			(effects
				(font
					(size 0.7874 0.5842)
					(thickness 0.1524)
				)
				(justify mirror)
			)
		)
		(property "User Part Number" "PARTNUM*"
			(at -0.1016 4.023106 90)
			(unlocked yes)
			(layer "Cmts.User")
			(hide yes)
			(effects
				(font
					(size 0.7874 0.5842)
					(thickness 0.1524)
				)
				(justify mirror)
			)
		)
		(property "Tolerance" "TOL*"
			(at -0.0762 3.032506 90)
			(unlocked yes)
			(layer "Cmts.User")
			(hide yes)
			(effects
				(font
					(size 0.7874 0.5842)
					(thickness 0.1524)
				)
				(justify mirror)
			)
		)
		(duplicate_pad_numbers_are_jumpers no)
		(fp_line
			(start 1.143 -0.5588)
			(end 1.143 0.5588)
			(stroke
				(width 0.1)
				(type default)
			)
			(layer "B.SilkS")
		)
		(fp_line
			(start -1.143 -0.5588)
			(end 1.143 -0.5588)
			(stroke
				(width 0.1)
				(type default)
			)
			(layer "B.SilkS")
		)
		(fp_line
			(start 1.143 0.5588)
			(end -1.143 0.5588)
			(stroke
				(width 0.1)
				(type default)
			)
			(layer "B.SilkS")
		)
		(fp_line
			(start -1.143 0.5588)
			(end -1.143 -0.5588)
			(stroke
				(width 0.1)
				(type default)
			)
			(layer "B.SilkS")
		)
		(fp_rect
			(start -1.143 -0.5588)
			(end 1.143 0.5588)
			(stroke
				(width 0)
				(type default)
			)
			(fill no)
			(layer "B.CrtYd")
		)
		(fp_line
			(start 0.508 -0.3048)
			(end 0.508 0.3048)
			(stroke
				(width 0.1)
				(type default)
			)
			(layer "B.Fab")
		)
		(fp_line
			(start -0.508 -0.3048)
			(end 0.508 -0.3048)
			(stroke
				(width 0.1)
				(type default)
			)
			(layer "B.Fab")
		)
		(fp_line
			(start 0.508 0.3048)
			(end -0.508 0.3048)
			(stroke
				(width 0.1)
				(type default)
			)
			(layer "B.Fab")
		)
		(fp_line
			(start -0.508 0.3048)
			(end -0.508 -0.3048)
			(stroke
				(width 0.1)
				(type default)
			)
			(layer "B.Fab")
		)
		(pad "1" smd rect
			(at 0.5334 0 270)
			(size 0.7112 0.6096)
			(layers "B.Cu" "B.Mask" "B.Paste")
			(net "XP3R3V")
		)
		(pad "2" smd rect
			(at -0.5334 0 270)
			(size 0.7112 0.6096)
			(layers "B.Cu" "B.Mask" "B.Paste")
			(net "SG")
		)
		(zone
			(layer "B.Cu")
			(hatch none 0.5)
			(connect_pads
				(clearance 0)
			)
			(min_thickness 0.25)
			(keepout
				(tracks allowed)
				(vias not_allowed)
				(pads allowed)
				(copperpour not_allowed)
				(footprints allowed)
			)
			(placement
				(enabled no)
				(sheetname "")
			)
			(fill
				(thermal_gap 0.5)
				(thermal_bridge_width 0.5)
				(island_removal_mode 0)
			)
			(polygon
				(pts
					(xy 95.4532 -19.9898) (xy 96.0628 -19.9898) (xy 96.0628 -20.1422) (xy 95.4532 -20.1422)
				)
			)
		)
	)
	(footprint ""
		(layer "B.Cu")
		(at 33.7693 -16.7132)
		(property "Reference" "R175"
			(at 0.7747 1.89357 0)
			(unlocked yes)
			(layer "B.SilkS")
			(effects
				(font
					(size 0.7874 0.5842)
					(thickness 0.1524)
				)
				(justify mirror)
			)
		)
		(property "Value" "VAL*"
			(at -0.02032 2.13233 0)
			(unlocked yes)
			(layer "B.Fab")
			(hide yes)
			(effects
				(font
					(size 0.7874 0.5842)
					(thickness 0.1524)
				)
				(justify mirror)
			)
		)
		(property "Tolerance" "TOL*"
			(at -0.044704 3.05435 0)
			(unlocked yes)
			(layer "Cmts.User")
			(hide yes)
			(effects
				(font
					(size 0.7874 0.5842)
					(thickness 0.1524)
				)
				(justify mirror)
			)
		)
		(property "User Part Number" "PARTNUM*"
			(at -0.02032 4.024884 0)
			(unlocked yes)
			(layer "Cmts.User")
			(hide yes)
			(effects
				(font
					(size 0.7874 0.5842)
					(thickness 0.1524)
				)
				(justify mirror)
			)
		)
		(property "Device Type" "RESISTOR-G155-133R0-01,33OHM,1%"
			(at -0.008382 1.210564 0)
			(unlocked yes)
			(layer "B.Fab")
			(hide yes)
			(effects
				(font
					(size 0.7874 0.5842)
					(thickness 0.1524)
				)
				(justify mirror)
			)
		)
		(duplicate_pad_numbers_are_jumpers no)
		(fp_line
			(start -1.143 -0.5588)
			(end 1.143 -0.5588)
			(stroke
				(width 0.1)
				(type default)
			)
			(layer "B.SilkS")
		)
		(fp_line
			(start -1.143 0.5588)
			(end -1.143 -0.5588)
			(stroke
				(width 0.1)
				(type default)
			)
			(layer "B.SilkS")
		)
		(fp_line
			(start 1.143 -0.5588)
			(end 1.143 0.5588)
			(stroke
				(width 0.1)
				(type default)
			)
			(layer "B.SilkS")
		)
		(fp_line
			(start 1.143 0.5588)
			(end -1.143 0.5588)
			(stroke
				(width 0.1)
				(type default)
			)
			(layer "B.SilkS")
		)
		(fp_rect
			(start -1.143 0.5588)
			(end 1.143 -0.5588)
			(stroke
				(width 0)
				(type default)
			)
			(fill no)
			(layer "B.CrtYd")
		)
		(fp_line
			(start -0.508 -0.3048)
			(end 0.508 -0.3048)
			(stroke
				(width 0.1)
				(type default)
			)
			(layer "B.Fab")
		)
		(fp_line
			(start -0.508 0.3048)
			(end -0.508 -0.3048)
			(stroke
				(width 0.1)
				(type default)
			)
			(layer "B.Fab")
		)
		(fp_line
			(start 0.508 -0.3048)
			(end 0.508 0.3048)
			(stroke
				(width 0.1)
				(type default)
			)
			(layer "B.Fab")
		)
		(fp_line
			(start 0.508 0.3048)
			(end -0.508 0.3048)
			(stroke
				(width 0.1)
				(type default)
			)
			(layer "B.Fab")
		)
		(pad "1" smd rect
			(at 0.5334 0 180)
			(size 0.7112 0.6096)
			(layers "B.Cu" "B.Mask" "B.Paste")
			(net "PCIE_SMDAT")
		)
		(pad "2" smd rect
			(at -0.5334 0 180)
			(size 0.7112 0.6096)
			(layers "B.Cu" "B.Mask" "B.Paste")
			(net "EEPROM_SDA")
		)
		(zone
			(layer "B.Cu")
			(hatch none 0.5)
			(connect_pads
				(clearance 0)
			)
			(min_thickness 0.25)
			(keepout
				(tracks allowed)
				(vias not_allowed)
				(pads allowed)
				(copperpour not_allowed)
				(footprints allowed)
			)
			(placement
				(enabled no)
				(sheetname "")
			)
			(fill
				(thermal_gap 0.5)
				(thermal_bridge_width 0.5)
				(island_removal_mode 0)
			)
			(polygon
				(pts
					(xy 33.6931 -16.4084) (xy 33.8455 -16.4084) (xy 33.8455 -17.018) (xy 33.6931 -17.018)
				)
			)
		)
	)
)
